(kicad_pcb
	(version 20241229)
	(generator "pcbnew")
	(generator_version "9.0")
	(general
		(thickness 1.6296)
		(legacy_teardrops no)
	)
	(paper "A3")
	(title_block
		(title "Thunderbolt to 10GbE adapter")
		(date "2026-04-21")
		(rev "1.1.0")
		(company "Antmicro Ltd")
		(comment 1 "www.antmicro.com")
		(comment 9 "footprints 110-113 of 703")
	)
	(layers
		(0 "F.Cu" signal)
		(4 "In1.Cu" signal)
		(6 "In2.Cu" signal)
		(8 "In3.Cu" signal)
		(10 "In4.Cu" signal)
		(12 "In5.Cu" signal)
		(14 "In6.Cu" signal)
		(2 "B.Cu" signal)
		(9 "F.Adhes" user "F.Adhesive")
		(11 "B.Adhes" user "B.Adhesive")
		(13 "F.Paste" user)
		(15 "B.Paste" user)
		(5 "F.SilkS" user "F.Silkscreen")
		(7 "B.SilkS" user "B.Silkscreen")
		(1 "F.Mask" user)
		(3 "B.Mask" user)
		(17 "Dwgs.User" user "User.Drawings")
		(19 "Cmts.User" user "User.Comments")
		(21 "Eco1.User" user "User.Eco1")
		(23 "Eco2.User" user "User.Eco2")
		(25 "Edge.Cuts" user)
		(27 "Margin" user)
		(31 "F.CrtYd" user "F.Courtyard")
		(29 "B.CrtYd" user "B.Courtyard")
		(35 "F.Fab" user)
		(33 "B.Fab" user)
	)
	(footprint "antmicro-footprints:C_0402_1005Metric"
		(layer "F.Cu")
		(at 160.105 69.075 90)
		(descr "Capacitor SMD 0402")
		(tags "capacitor SMD 0402")
		(property "Reference" "C286"
			(at 11.574999 20.295 90)
			(layer "F.SilkS")
			(effects
				(font
					(size 0.7 0.7)
					(thickness 0.15)
				)
			)
		)
		(property "Value" "C_100n_0402"
			(at -1.022927 2.155213 90)
			(layer "F.Fab")
			(effects
				(font
					(size 0.7 0.7)
					(thickness 0.15)
				)
				(justify left bottom)
			)
		)
		(property "Datasheet" "https://www.murata.com/products/productdetail?partno=GRM155R61H104KE14%23"
			(at 0 0 90)
			(layer "F.Fab")
			(hide yes)
			(effects
				(font
					(size 1.27 1.27)
					(thickness 0.15)
				)
			)
		)
		(property "Description" "SMD Multilayer Ceramic Capacitor, 0.1 µF, 50 V, 0402 [1005 Metric], ± 10%, X5R, GRM Series"
			(at 0 0 90)
			(layer "F.Fab")
			(hide yes)
			(effects
				(font
					(size 1.27 1.27)
					(thickness 0.15)
				)
			)
		)
		(property "MPN" "GRM155R61H104KE14D"
			(at 0 0 90)
			(unlocked yes)
			(layer "F.Fab")
			(hide yes)
			(effects
				(font
					(size 1 1)
					(thickness 0.15)
				)
			)
		)
		(property "Val" "100n"
			(at 0 0 90)
			(unlocked yes)
			(layer "F.Fab")
			(hide yes)
			(effects
				(font
					(size 1 1)
					(thickness 0.15)
				)
			)
		)
		(property "Voltage" "50V"
			(at 0 0 90)
			(unlocked yes)
			(layer "F.Fab")
			(hide yes)
			(effects
				(font
					(size 1 1)
					(thickness 0.15)
				)
			)
		)
		(property "Dielectric" "X5R"
			(at 0 0 90)
			(unlocked yes)
			(layer "F.Fab")
			(hide yes)
			(effects
				(font
					(size 1 1)
					(thickness 0.15)
				)
			)
		)
		(property "Manufacturer" "Murata"
			(at 0 0 90)
			(unlocked yes)
			(layer "F.Fab")
			(hide yes)
			(effects
				(font
					(size 1 1)
					(thickness 0.15)
				)
			)
		)
		(property "License" "Apache-2.0"
			(at 0 0 90)
			(unlocked yes)
			(layer "F.Fab")
			(hide yes)
			(effects
				(font
					(size 1 1)
					(thickness 0.15)
				)
			)
		)
		(property "Author" "Antmicro"
			(at 0 0 90)
			(unlocked yes)
			(layer "F.Fab")
			(hide yes)
			(effects
				(font
					(size 1 1)
					(thickness 0.15)
				)
			)
		)
		(sheetname "/X710-AT2 10GbE/")
		(sheetfile "x710-at2-10gbe.kicad_sch")
		(attr smd)
		(fp_rect
			(start -0.925 -0.47)
			(end 0.925 0.47)
			(stroke
				(width 0.05)
				(type default)
			)
			(fill no)
			(layer "F.CrtYd")
		)
		(fp_line
			(start 0.504 -0.25)
			(end 0.504 0.248)
			(stroke
				(width 0.15)
				(type solid)
			)
			(layer "F.Fab")
		)
		(fp_line
			(start -0.494 -0.25)
			(end 0.504 -0.25)
			(stroke
				(width 0.15)
				(type solid)
			)
			(layer "F.Fab")
		)
		(fp_line
			(start 0.504 0.248)
			(end -0.494 0.248)
			(stroke
				(width 0.15)
				(type solid)
			)
			(layer "F.Fab")
		)
		(fp_line
			(start -0.494 0.248)
			(end -0.494 -0.25)
			(stroke
				(width 0.15)
				(type solid)
			)
			(layer "F.Fab")
		)
		(fp_text user "${REFERENCE}"
			(at -0.939 4.599 90)
			(layer "F.Fab")
			(effects
				(font
					(size 0.7 0.7)
					(thickness 0.15)
				)
				(justify left bottom)
			)
		)
		(fp_text user "License: Apache-2.0"
			(at -0.939 5.799 90)
			(layer "F.Fab")
			(effects
				(font
					(size 0.7 0.7)
					(thickness 0.15)
				)
				(justify left bottom)
			)
		)
		(fp_text user "Author: Antmicro"
			(at -0.939 3.399 90)
			(layer "F.Fab")
			(effects
				(font
					(size 0.7 0.7)
					(thickness 0.15)
				)
				(justify left bottom)
			)
		)
		(pad "1" smd roundrect
			(at -0.48 0 90)
			(size 0.59 0.64)
			(layers "F.Cu" "F.Mask" "F.Paste")
			(roundrect_rratio 0.25)
			(net 26 "/X710-AT2 10GbE/25MHZ_OSC.-")
			(pintype "passive")
		)
		(pad "2" smd roundrect
			(at 0.48 0 90)
			(size 0.59 0.64)
			(layers "F.Cu" "F.Mask" "F.Paste")
			(roundrect_rratio 0.25)
			(net 55 "/X710-AT2 10GbE/25MHZ_OSC_AC.-")
			(pintype "passive")
		)
	)
	(footprint "antmicro-footprints:C_0603_1608Metric_EIA"
		(layer "F.Cu")
		(at 133.105001 99.774999 -90)
		(descr "Capacitor SMD 0603, IPC-7351 Density Level A")
		(tags "Capacitor 0603")
		(property "Reference" "C252"
			(at -9.274999 -38.13 270)
			(layer "F.SilkS")
			(effects
				(font
					(size 0.7 0.7)
					(thickness 0.15)
				)
			)
		)
		(property "Value" "C_22u_16V_0603"
			(at -1.42757 1.770288 270)
			(layer "F.Fab")
			(effects
				(font
					(size 0.7 0.7)
					(thickness 0.15)
				)
				(justify left bottom)
			)
		)
		(property "Datasheet" "https://product.samsungsem.com/mlcc/CL10A226MO7JZN.do"
			(at 0 0 270)
			(layer "F.Fab")
			(hide yes)
			(effects
				(font
					(size 1.27 1.27)
					(thickness 0.15)
				)
			)
		)
		(property "Description" "SMD Multilayer Ceramic Capacitor"
			(at 0 0 270)
			(layer "F.Fab")
			(hide yes)
			(effects
				(font
					(size 1.27 1.27)
					(thickness 0.15)
				)
			)
		)
		(property "MPN" "CL10A226MO7JZNC"
			(at 0 0 270)
			(unlocked yes)
			(layer "F.Fab")
			(hide yes)
			(effects
				(font
					(size 1 1)
					(thickness 0.15)
				)
			)
		)
		(property "Manufacturer" "Samsung Electro-Mechanics"
			(at 0 0 270)
			(unlocked yes)
			(layer "F.Fab")
			(hide yes)
			(effects
				(font
					(size 1 1)
					(thickness 0.15)
				)
			)
		)
		(property "License" "Apache-2.0"
			(at 0 0 270)
			(unlocked yes)
			(layer "F.Fab")
			(hide yes)
			(effects
				(font
					(size 1 1)
					(thickness 0.15)
				)
			)
		)
		(property "Author" "Antmicro"
			(at 0 0 270)
			(unlocked yes)
			(layer "F.Fab")
			(hide yes)
			(effects
				(font
					(size 1 1)
					(thickness 0.15)
				)
			)
		)
		(property "Val" "22u"
			(at 0 0 270)
			(unlocked yes)
			(layer "F.Fab")
			(hide yes)
			(effects
				(font
					(size 1 1)
					(thickness 0.15)
				)
			)
		)
		(property "Voltage" "16V"
			(at 0 0 270)
			(unlocked yes)
			(layer "F.Fab")
			(hide yes)
			(effects
				(font
					(size 1 1)
					(thickness 0.15)
				)
			)
		)
		(property "Dielectric" ""
			(at 0 0 270)
			(unlocked yes)
			(layer "F.Fab")
			(hide yes)
			(effects
				(font
					(size 1 1)
					(thickness 0.15)
				)
			)
		)
		(sheetname "/X710-AT2 power/")
		(sheetfile "x710-at2-power.kicad_sch")
		(attr smd)
		(fp_line
			(start -0.15 0.55)
			(end 0.15 0.55)
			(stroke
				(width 0.15)
				(type solid)
			)
			(layer "F.SilkS")
		)
		(fp_line
			(start -0.15 -0.55)
			(end 0.15 -0.55)
			(stroke
				(width 0.15)
				(type solid)
			)
			(layer "F.SilkS")
		)
		(fp_rect
			(start -1.25 -0.65)
			(end 1.25 0.65)
			(stroke
				(width 0.05)
				(type solid)
			)
			(fill no)
			(layer "F.CrtYd")
		)
		(fp_rect
			(start -0.8 -0.45)
			(end 0.8 0.45)
			(stroke
				(width 0.15)
				(type solid)
			)
			(fill no)
			(layer "F.Fab")
		)
		(fp_text user "Author: Antmicro"
			(at -1.682 4.894 270)
			(layer "F.Fab")
			(effects
				(font
					(size 0.7 0.7)
					(thickness 0.15)
				)
				(justify left bottom)
			)
		)
		(fp_text user "${REFERENCE}"
			(at -1.682 3.895 270)
			(layer "F.Fab")
			(effects
				(font
					(size 0.7 0.7)
					(thickness 0.15)
				)
				(justify left bottom)
			)
		)
		(fp_text user "License: Apache-2.0"
			(at -1.682 5.895 270)
			(layer "F.Fab")
			(effects
				(font
					(size 0.7 0.7)
					(thickness 0.15)
				)
				(justify left bottom)
			)
		)
		(pad "1" smd roundrect
			(at -0.7 0 270)
			(size 0.8 1.1)
			(layers "F.Cu" "F.Mask" "F.Paste")
			(roundrect_rratio 0.2)
			(net 23 "GND")
			(pintype "passive")
		)
		(pad "2" smd roundrect
			(at 0.7 0 270)
			(size 0.8 1.1)
			(layers "F.Cu" "F.Mask" "F.Paste")
			(roundrect_rratio 0.2)
			(net 9 "VCCD")
			(pintype "passive")
		)
	)
	(footprint "antmicro-footprints:C_0402_1005Metric"
		(layer "F.Cu")
		(at 162.6 111.85)
		(descr "Capacitor SMD 0402")
		(tags "capacitor SMD 0402")
		(property "Reference" "C117"
			(at 12.450003 16.799998 0)
			(layer "F.SilkS")
			(effects
				(font
					(size 0.7 0.7)
					(thickness 0.15)
				)
			)
		)
		(property "Value" "C_100n_0402"
			(at -1.022927 2.155213 0)
			(layer "F.Fab")
			(effects
				(font
					(size 0.7 0.7)
					(thickness 0.15)
				)
				(justify left bottom)
			)
		)
		(property "Datasheet" "https://www.murata.com/products/productdetail?partno=GRM155R61H104KE14%23"
			(at 0 0 0)
			(layer "F.Fab")
			(hide yes)
			(effects
				(font
					(size 1.27 1.27)
					(thickness 0.15)
				)
			)
		)
		(property "Description" "SMD Multilayer Ceramic Capacitor, 0.1 µF, 50 V, 0402 [1005 Metric], ± 10%, X5R, GRM Series"
			(at 0 0 0)
			(layer "F.Fab")
			(hide yes)
			(effects
				(font
					(size 1.27 1.27)
					(thickness 0.15)
				)
			)
		)
		(property "MPN" "GRM155R61H104KE14D"
			(at 0 0 0)
			(unlocked yes)
			(layer "F.Fab")
			(hide yes)
			(effects
				(font
					(size 1 1)
					(thickness 0.15)
				)
			)
		)
		(property "Manufacturer" "Murata"
			(at 0 0 0)
			(unlocked yes)
			(layer "F.Fab")
			(hide yes)
			(effects
				(font
					(size 1 1)
					(thickness 0.15)
				)
			)
		)
		(property "License" "Apache-2.0"
			(at 0 0 0)
			(unlocked yes)
			(layer "F.Fab")
			(hide yes)
			(effects
				(font
					(size 1 1)
					(thickness 0.15)
				)
			)
		)
		(property "Author" "Antmicro"
			(at 0 0 0)
			(unlocked yes)
			(layer "F.Fab")
			(hide yes)
			(effects
				(font
					(size 1 1)
					(thickness 0.15)
				)
			)
		)
		(property "Val" "100n"
			(at 0 0 0)
			(unlocked yes)
			(layer "F.Fab")
			(hide yes)
			(effects
				(font
					(size 1 1)
					(thickness 0.15)
				)
			)
		)
		(property "Voltage" "50V"
			(at 0 0 0)
			(unlocked yes)
			(layer "F.Fab")
			(hide yes)
			(effects
				(font
					(size 1 1)
					(thickness 0.15)
				)
			)
		)
		(property "Dielectric" "X5R"
			(at 0 0 0)
			(unlocked yes)
			(layer "F.Fab")
			(hide yes)
			(effects
				(font
					(size 1 1)
					(thickness 0.15)
				)
			)
		)
		(sheetname "/X710 DCDC converters/")
		(sheetfile "DCDC_converters_X710.kicad_sch")
		(attr smd)
		(fp_rect
			(start -0.925 -0.47)
			(end 0.925 0.47)
			(stroke
				(width 0.05)
				(type default)
			)
			(fill no)
			(layer "F.CrtYd")
		)
		(fp_line
			(start -0.494 -0.25)
			(end 0.504 -0.25)
			(stroke
				(width 0.15)
				(type solid)
			)
			(layer "F.Fab")
		)
		(fp_line
			(start -0.494 0.248)
			(end -0.494 -0.25)
			(stroke
				(width 0.15)
				(type solid)
			)
			(layer "F.Fab")
		)
		(fp_line
			(start 0.504 -0.25)
			(end 0.504 0.248)
			(stroke
				(width 0.15)
				(type solid)
			)
			(layer "F.Fab")
		)
		(fp_line
			(start 0.504 0.248)
			(end -0.494 0.248)
			(stroke
				(width 0.15)
				(type solid)
			)
			(layer "F.Fab")
		)
		(fp_text user "${REFERENCE}"
			(at -0.939 4.599 0)
			(layer "F.Fab")
			(effects
				(font
					(size 0.7 0.7)
					(thickness 0.15)
				)
				(justify left bottom)
			)
		)
		(fp_text user "License: Apache-2.0"
			(at -0.939 5.799 0)
			(layer "F.Fab")
			(effects
				(font
					(size 0.7 0.7)
					(thickness 0.15)
				)
				(justify left bottom)
			)
		)
		(fp_text user "Author: Antmicro"
			(at -0.939 3.399 0)
			(layer "F.Fab")
			(effects
				(font
					(size 0.7 0.7)
					(thickness 0.15)
				)
				(justify left bottom)
			)
		)
		(pad "1" smd roundrect
			(at -0.48 0)
			(size 0.59 0.64)
			(layers "F.Cu" "F.Mask" "F.Paste")
			(roundrect_rratio 0.25)
			(net 23 "GND")
			(pintype "passive")
		)
		(pad "2" smd roundrect
			(at 0.48 0)
			(size 0.59 0.64)
			(layers "F.Cu" "F.Mask" "F.Paste")
			(roundrect_rratio 0.25)
			(net 40 "+5V")
			(pintype "passive")
		)
	)
	(footprint "antmicro-footprints:LED_0603_1608Metric_G"
		(layer "F.Cu")
		(at 135 143.5 -90)
		(descr "LED SMD 0603 Green")
		(tags "LED SMD 0603 Green")
		(property "Reference" "D11"
			(at 1 0.8 270)
			(layer "F.SilkS")
			(effects
				(font
					(size 0.7 0.7)
					(thickness 0.15)
				)
				(justify left bottom)
			)
		)
		(property "Value" "LED_G_0603_LG_L29K-G2J1-24-Z"
			(at -0.001 1.599 270)
			(layer "F.Fab")
			(effects
				(font
					(size 0.7 0.7)
					(thickness 0.15)
				)
				(justify left bottom)
			)
		)
		(property "Datasheet" "https://look.ams-osram.com/m/19ee86b3ae0ee95b/original/LG-L29K.pdf"
			(at 0 0 270)
			(layer "F.Fab")
			(hide yes)
			(effects
				(font
					(size 1.27 1.27)
					(thickness 0.15)
				)
			)
		)
		(property "Description" "LED, Green, SMD, 0603, 20 mA, 1.7 V, 570 nm"
			(at 0 0 270)
			(layer "F.Fab")
			(hide yes)
			(effects
				(font
					(size 1.27 1.27)
					(thickness 0.15)
				)
			)
		)
		(property "MPN" "LG L29K-G2J1-24-Z"
			(at 0 0 270)
			(unlocked yes)
			(layer "F.Fab")
			(hide yes)
			(effects
				(font
					(size 1 1)
					(thickness 0.15)
				)
			)
		)
		(property "Manufacturer" "OSRAM"
			(at 0 0 270)
			(unlocked yes)
			(layer "F.Fab")
			(hide yes)
			(effects
				(font
					(size 1 1)
					(thickness 0.15)
				)
			)
		)
		(property "Color" "Green"
			(at 0 0 270)
			(unlocked yes)
			(layer "F.Fab")
			(hide yes)
			(effects
				(font
					(size 1 1)
					(thickness 0.15)
				)
			)
		)
		(property "Author" "Antmicro"
			(at 0 0 270)
			(unlocked yes)
			(layer "F.Fab")
			(hide yes)
			(effects
				(font
					(size 1 1)
					(thickness 0.15)
				)
			)
		)
		(property "License" "Apache-2.0"
			(at 0 0 270)
			(unlocked yes)
			(layer "F.Fab")
			(hide yes)
			(effects
				(font
					(size 1 1)
					(thickness 0.15)
				)
			)
		)
		(sheetname "/X710 DCDC converters/")
		(sheetfile "DCDC_converters_X710.kicad_sch")
		(attr smd)
		(fp_line
			(start 0.22 0.35)
			(end -0.22 0.35)
			(stroke
				(width 0.15)
				(type solid)
			)
			(layer "F.SilkS")
		)
		(fp_line
			(start -0.094672 0.201008)
			(end -0.094672 -0.198992)
			(stroke
				(width 0.1)
				(type solid)
			)
			(layer "F.SilkS")
		)
		(fp_line
			(start 0.105328 0.201008)
			(end -0.094672 0.001008)
			(stroke
				(width 0.1)
				(type solid)
			)
			(layer "F.SilkS")
		)
		(fp_line
			(start 0.105328 0.201008)
			(end 0.105328 -0.198992)
			(stroke
				(width 0.1)
				(type solid)
			)
			(layer "F.SilkS")
		)
		(fp_line
			(start -0.094672 0.001008)
			(end -0.24 0.001008)
			(stroke
				(width 0.1)
				(type solid)
			)
			(layer "F.SilkS")
		)
		(fp_line
			(start -0.094672 0.001008)
			(end 0.105328 -0.198992)
			(stroke
				(width 0.1)
				(type solid)
			)
			(layer "F.SilkS")
		)
		(fp_line
			(start 0.105328 0.001008)
			(end 0.24 0.001)
			(stroke
				(width 0.1)
				(type solid)
			)
			(layer "F.SilkS")
		)
		(fp_line
			(start -1.18 -0.319)
			(end -1.18 0.321)
			(stroke
				(width 0.15)
				(type solid)
			)
			(layer "F.SilkS")
		)
		(fp_line
			(start 0.22 -0.35)
			(end -0.22 -0.35)
			(stroke
				(width 0.15)
				(type solid)
			)
			(layer "F.SilkS")
		)
		(fp_rect
			(start 1.25 0.65)
			(end -1.25 -0.65)
			(stroke
				(width 0.05)
				(type solid)
			)
			(fill no)
			(layer "F.CrtYd")
		)
		(fp_line
			(start -0.199 0.2)
			(end -0.199 0.1)
			(stroke
				(width 0.15)
				(type solid)
			)
			(layer "F.Fab")
		)
		(fp_line
			(start 0.201 0.2)
			(end 0.201 0)
			(stroke
				(width 0.15)
				(type solid)
			)
			(layer "F.Fab")
		)
		(fp_line
			(start -0.199 0)
			(end -0.597 0)
			(stroke
				(width 0.15)
				(type solid)
			)
			(layer "F.Fab")
		)
		(fp_line
			(start -0.101 0)
			(end 0.201 0.2)
			(stroke
				(width 0.15)
				(type solid)
			)
			(layer "F.Fab")
		)
		(fp_line
			(start 0.201 0)
			(end 0.201 -0.202)
			(stroke
				(width 0.15)
				(type solid)
			)
			(layer "F.Fab")
		)
		(fp_line
			(start 0.599 0)
			(end 0.201 0)
			(stroke
				(width 0.15)
				(type solid)
			)
			(layer "F.Fab")
		)
		(fp_line
			(start -0.199 -0.202)
			(end -0.199 0.1)
			(stroke
				(width 0.15)
				(type solid)
			)
			(layer "F.Fab")
		)
		(fp_line
			(start 0.201 -0.202)
			(end -0.101 0)
			(stroke
				(width 0.15)
				(type solid)
			)
			(layer "F.Fab")
		)
		(fp_rect
			(start 0.848 0.4)
			(end -0.85 -0.402)
			(stroke
				(width 0.15)
				(type solid)
			)
			(fill no)
			(layer "F.Fab")
		)
		(fp_text user "License: Apache-2.0"
			(at -1.4224 3.599 270)
			(layer "F.Fab")
			(effects
				(font
					(size 0.7 0.7)
					(thickness 0.15)
				)
				(justify left bottom)
			)
		)
		(fp_text user "${REFERENCE}"
			(at -1.4224 5.999 270)
			(layer "F.Fab")
			(effects
				(font
					(size 0.7 0.7)
					(thickness 0.15)
				)
				(justify left bottom)
			)
		)
		(fp_text user "Author: Antmicro"
			(at -1.4224 4.799 270)
			(layer "F.Fab")
			(effects
				(font
					(size 0.7 0.7)
					(thickness 0.15)
				)
				(justify left bottom)
			)
		)
		(pad "1" smd roundrect
			(at -0.7 0 90)
			(size 0.8 1)
			(layers "F.Cu" "F.Mask" "F.Paste")
			(roundrect_rratio 0.2)
			(net 418 "Net-(D11-C)")
			(pinfunction "C")
			(pintype "passive")
		)
		(pad "2" smd roundrect
			(at 0.7 0 90)
			(size 0.8 1)
			(layers "F.Cu" "F.Mask" "F.Paste")
			(roundrect_rratio 0.2)
			(net 419 "Net-(D11-A)")
			(pinfunction "A")
			(pintype "passive")
		)
	)
)
